# SCM (Grand Teton) — schematic netlist excerpt (pin names and nets, part order shuffled) for the footprints in the layout excerpt that follows; sources: Cadence DE-HDL packaged netlist, KiCad conversion of 12092022_DA0F0TMDCD0_F0T_Management_Board_D_brd_V3_OCP.brd

R630  Q_RES  4.7K 1% CHIP  pkg 0402LF  page 31 : A = P3V3_AUX ; B = PU_J13_P1
C225  Q_CAP  0.1UF 25V 10% X7R  pkg 0402  page 20 : A = P1V2_AUX ; B = GND

(kicad_pcb
	(version 20260206)
	(generator "pcbnew")
	(generator_version "10.0")
	(general
		(thickness 1.6)
		(legacy_teardrops no)
	)
	(paper "A4")
	(title_block
		(title "12092022_DA0F0TMDCD0_F0T_Management_Board_D_brd_V3_OCP.brd")
		(comment 1 "Grand Teton / footprints 1213-1214 of 1440")
	)
	(layers
		(0 "F.Cu" signal "TOP")
		(4 "In1.Cu" signal "GND")
		(6 "In2.Cu" signal "IN1")
		(8 "In3.Cu" signal "GND1")
		(10 "In4.Cu" signal "IN2")
		(12 "In5.Cu" signal "VCC")
		(14 "In6.Cu" signal "VCC1")
		(16 "In7.Cu" signal "IN3")
		(18 "In8.Cu" signal "GND2")
		(20 "In9.Cu" signal "IN4")
		(22 "In10.Cu" signal "GND3")
		(2 "B.Cu" signal "BOTTOM")
		(9 "F.Adhes" user "F.Adhesive")
		(11 "B.Adhes" user "B.Adhesive")
		(13 "F.Paste" user "Package Geometry/Pastemask Top")
		(15 "B.Paste" user "Package Geometry/Pastemask Bottom")
		(5 "F.SilkS" user "Ref Des/Silkscreen Top")
		(7 "B.SilkS" user "Ref Des/Silkscreen Bottom")
		(1 "F.Mask" user "Board Geometry/Soldermask Top")
		(3 "B.Mask" user "Board Geometry/Soldermask Bottom")
		(17 "Dwgs.User" user "User.Drawings")
		(19 "Cmts.User" user "User.Comments")
		(21 "Eco1.User" user "User.Eco1")
		(23 "Eco2.User" user "User.Eco2")
		(25 "Edge.Cuts" user "Board Geometry/Outline")
		(27 "Margin" user)
		(31 "F.CrtYd" user "Package Geometry/Place Bound Top")
		(29 "B.CrtYd" user "Package Geometry/Place Bound Bottom")
		(35 "F.Fab" user "Ref Des/Assembly Top")
		(33 "B.Fab" user "Ref Des/Assembly Bottom")
	)
	(footprint ""
		(layer "B.Cu")
		(at 70.104 -41.656 90)
		(property "Reference" "C225"
			(at 0 0 90)
			(layer "B.SilkS")
			(hide yes)
			(effects
				(font
					(size 1.27 1.27)
				)
				(justify mirror)
			)
		)
		(property "Value" ""
			(at 0 0 90)
			(layer "B.Fab")
			(effects
				(font
					(size 1.27 1.27)
				)
				(justify mirror)
			)
		)
		(duplicate_pad_numbers_are_jumpers no)
		(fp_line
			(start 0.7874 -0.4064)
			(end -0.7874 -0.4064)
			(stroke
				(width 0.1524)
				(type default)
			)
			(layer "B.SilkS")
		)
		(fp_line
			(start -0.7874 -0.4064)
			(end -0.7874 0.4064)
			(stroke
				(width 0.1524)
				(type default)
			)
			(layer "B.SilkS")
		)
		(fp_line
			(start 0.7874 0.4064)
			(end 0.7874 -0.4064)
			(stroke
				(width 0.1524)
				(type default)
			)
			(layer "B.SilkS")
		)
		(fp_line
			(start -0.7874 0.4064)
			(end 0.7874 0.4064)
			(stroke
				(width 0.1524)
				(type default)
			)
			(layer "B.SilkS")
		)
		(fp_line
			(start 0.67945 -0.305054)
			(end 0.12065 -0.305054)
			(stroke
				(width 0.1)
				(type default)
			)
			(layer "B.Fab")
		)
		(fp_line
			(start 0.12065 -0.305054)
			(end 0.12065 -0.2794)
			(stroke
				(width 0.1)
				(type default)
			)
			(layer "B.Fab")
		)
		(fp_line
			(start -0.12065 -0.3048)
			(end -0.67945 -0.3048)
			(stroke
				(width 0.1)
				(type default)
			)
			(layer "B.Fab")
		)
		(fp_line
			(start -0.67945 -0.3048)
			(end -0.67945 0.3048)
			(stroke
				(width 0.1)
				(type default)
			)
			(layer "B.Fab")
		)
		(fp_line
			(start 0.12065 -0.2794)
			(end -0.12065 -0.2794)
			(stroke
				(width 0.1)
				(type default)
			)
			(layer "B.Fab")
		)
		(fp_line
			(start -0.12065 -0.2794)
			(end -0.12065 -0.3048)
			(stroke
				(width 0.1)
				(type default)
			)
			(layer "B.Fab")
		)
		(fp_line
			(start 0.12065 0.2794)
			(end 0.12065 0.3048)
			(stroke
				(width 0.1)
				(type default)
			)
			(layer "B.Fab")
		)
		(fp_line
			(start -0.120396 0.2794)
			(end 0.12065 0.2794)
			(stroke
				(width 0.1)
				(type default)
			)
			(layer "B.Fab")
		)
		(fp_line
			(start 0.67945 0.3048)
			(end 0.67945 -0.305054)
			(stroke
				(width 0.1)
				(type default)
			)
			(layer "B.Fab")
		)
		(fp_line
			(start 0.12065 0.3048)
			(end 0.67945 0.3048)
			(stroke
				(width 0.1)
				(type default)
			)
			(layer "B.Fab")
		)
		(fp_line
			(start -0.120396 0.3048)
			(end -0.120396 0.2794)
			(stroke
				(width 0.1)
				(type default)
			)
			(layer "B.Fab")
		)
		(fp_line
			(start -0.67945 0.3048)
			(end -0.120396 0.3048)
			(stroke
				(width 0.1)
				(type default)
			)
			(layer "B.Fab")
		)
		(pad "1" smd circle
			(at 0.40005 0 270)
			(size 0 0)
			(layers "B.Cu" "B.Mask" "B.Paste")
			(net "P1V2_AUX")
		)
		(pad "2" smd circle
			(at -0.40005 0 270)
			(size 0 0)
			(layers "B.Cu" "B.Mask" "B.Paste")
			(net "GND")
		)
	)
	(footprint ""
		(layer "B.Cu")
		(at 64.643 -13.081 180)
		(property "Reference" "R630"
			(at 0 0 0)
			(layer "B.SilkS")
			(hide yes)
			(effects
				(font
					(size 1.27 1.27)
				)
				(justify mirror)
			)
		)
		(property "Value" ""
			(at 0 0 0)
			(layer "B.Fab")
			(effects
				(font
					(size 1.27 1.27)
				)
				(justify mirror)
			)
		)
		(duplicate_pad_numbers_are_jumpers no)
		(fp_line
			(start 0.7874 0.4064)
			(end 0.7874 -0.4064)
			(stroke
				(width 0.1524)
				(type default)
			)
			(layer "B.SilkS")
		)
		(fp_line
			(start 0.7874 -0.4064)
			(end -0.7874 -0.4064)
			(stroke
				(width 0.1524)
				(type default)
			)
			(layer "B.SilkS")
		)
		(fp_line
			(start -0.7874 0.4064)
			(end 0.7874 0.4064)
			(stroke
				(width 0.1524)
				(type default)
			)
			(layer "B.SilkS")
		)
		(fp_line
			(start -0.7874 -0.4064)
			(end -0.7874 0.4064)
			(stroke
				(width 0.1524)
				(type default)
			)
			(layer "B.SilkS")
		)
		(fp_line
			(start 0.67945 0.3048)
			(end 0.67945 -0.305054)
			(stroke
				(width 0.1)
				(type default)
			)
			(layer "B.Fab")
		)
		(fp_line
			(start 0.67945 -0.305054)
			(end 0.12065 -0.305054)
			(stroke
				(width 0.1)
				(type default)
			)
			(layer "B.Fab")
		)
		(fp_line
			(start 0.12065 0.3048)
			(end 0.67945 0.3048)
			(stroke
				(width 0.1)
				(type default)
			)
			(layer "B.Fab")
		)
		(fp_line
			(start 0.12065 0.2794)
			(end 0.12065 0.3048)
			(stroke
				(width 0.1)
				(type default)
			)
			(layer "B.Fab")
		)
		(fp_line
			(start 0.12065 -0.2794)
			(end -0.12065 -0.2794)
			(stroke
				(width 0.1)
				(type default)
			)
			(layer "B.Fab")
		)
		(fp_line
			(start 0.12065 -0.305054)
			(end 0.12065 -0.2794)
			(stroke
				(width 0.1)
				(type default)
			)
			(layer "B.Fab")
		)
		(fp_line
			(start -0.120396 0.3048)
			(end -0.120396 0.2794)
			(stroke
				(width 0.1)
				(type default)
			)
			(layer "B.Fab")
		)
		(fp_line
			(start -0.120396 0.2794)
			(end 0.12065 0.2794)
			(stroke
				(width 0.1)
				(type default)
			)
			(layer "B.Fab")
		)
		(fp_line
			(start -0.12065 -0.2794)
			(end -0.12065 -0.3048)
			(stroke
				(width 0.1)
				(type default)
			)
			(layer "B.Fab")
		)
		(fp_line
			(start -0.12065 -0.3048)
			(end -0.67945 -0.3048)
			(stroke
				(width 0.1)
				(type default)
			)
			(layer "B.Fab")
		)
		(fp_line
			(start -0.67945 0.3048)
			(end -0.120396 0.3048)
			(stroke
				(width 0.1)
				(type default)
			)
			(layer "B.Fab")
		)
		(fp_line
			(start -0.67945 -0.3048)
			(end -0.67945 0.3048)
			(stroke
				(width 0.1)
				(type default)
			)
			(layer "B.Fab")
		)
		(pad "1" smd circle
			(at 0.40005 0)
			(size 0 0)
			(layers "B.Cu" "B.Mask" "B.Paste")
			(net "P3V3_AUX")
		)
		(pad "2" smd circle
			(at -0.40005 0)
			(size 0 0)
			(layers "B.Cu" "B.Mask" "B.Paste")
			(net "PU_J13_P1")
		)
	)
)
